(kicad_pcb
	(version 20260206)
	(generator "pcbnew")
	(generator_version "10.0")
	(general
		(thickness 1.6)
		(legacy_teardrops no)
	)
	(paper "A4")
	(title_block
		(title "Wiwynn_Tioga_Pass_MB.brd")
		(comment 1 "Tioga Pass / footprint 2988 of 4770 (J6U1), pads 124-243 of 291")
	)
	(layers
		(0 "F.Cu" signal "TOP")
		(4 "In1.Cu" signal "L2GND")
		(6 "In2.Cu" signal "L3")
		(8 "In3.Cu" signal "L4GND")
		(10 "In4.Cu" signal "L5")
		(12 "In5.Cu" signal "L6GND")
		(14 "In6.Cu" signal "L7VCC")
		(16 "In7.Cu" signal "L8VCC")
		(18 "In8.Cu" signal "L9GND")
		(20 "In9.Cu" signal "L10")
		(22 "In10.Cu" signal "L11GND")
		(24 "In11.Cu" signal "L12")
		(26 "In12.Cu" signal "L13GND")
		(2 "B.Cu" signal "BOTTOM")
		(9 "F.Adhes" user "F.Adhesive")
		(11 "B.Adhes" user "B.Adhesive")
		(13 "F.Paste" user "Package Geometry/Pastemask Top")
		(15 "B.Paste" user "Package Geometry/Pastemask Bottom")
		(5 "F.SilkS" user "Ref Des/Silkscreen Top")
		(7 "B.SilkS" user "Ref Des/Silkscreen Bottom")
		(1 "F.Mask" user "Board Geometry/Soldermask Top")
		(3 "B.Mask" user "Board Geometry/Soldermask Bottom")
		(17 "Dwgs.User" user "User.Drawings")
		(19 "Cmts.User" user "User.Comments")
		(21 "Eco1.User" user "User.Eco1")
		(23 "Eco2.User" user "User.Eco2")
		(25 "Edge.Cuts" user "Board Geometry/Outline")
		(27 "Margin" user)
		(31 "F.CrtYd" user "Package Geometry/Place Bound Top")
		(29 "B.CrtYd" user "Package Geometry/Place Bound Bottom")
		(35 "F.Fab" user "Ref Des/Assembly Top")
		(33 "B.Fab" user "Ref Des/Assembly Bottom")
	)
	(footprint ""
		(layer "B.Cu")
		(at 194.700398 -15.222982 90)
		(property "Reference" "J6U1"
			(at 2.530348 39.10711 0)
			(unlocked yes)
			(layer "B.SilkS")
			(effects
				(font
					(size 0.7874 0.5842)
					(thickness 0.1524)
				)
				(justify left mirror)
			)
		)
		(property "Value" ""
			(at 0 0 90)
			(layer "B.Fab")
			(effects
				(font
					(size 1.27 1.27)
				)
				(justify mirror)
			)
		)
		(duplicate_pad_numbers_are_jumpers no)
		(pad "121" smd rect
			(at 0 107.100116 270)
			(size 1.8034 0.508)
			(layers "B.Cu" "B.Mask" "B.Paste")
			(net "M_B_DQS_DP<15>")
		)
		(pad "122" smd rect
			(at 0 107.95 270)
			(size 1.8034 0.508)
			(layers "B.Cu" "B.Mask" "B.Paste")
			(net "M_B_DQS_DN<15>")
		)
		(pad "123" smd rect
			(at 0 108.799884 270)
			(size 1.8034 0.508)
			(layers "B.Cu" "B.Mask" "B.Paste")
			(net "GND")
		)
		(pad "124" smd rect
			(at 0 109.650022 270)
			(size 1.8034 0.508)
			(layers "B.Cu" "B.Mask" "B.Paste")
			(net "M_B_DQ<54>")
		)
		(pad "125" smd rect
			(at 0 110.499906 270)
			(size 1.8034 0.508)
			(layers "B.Cu" "B.Mask" "B.Paste")
			(net "GND")
		)
		(pad "126" smd rect
			(at 0 111.350044 270)
			(size 1.8034 0.508)
			(layers "B.Cu" "B.Mask" "B.Paste")
			(net "M_B_DQ<50>")
		)
		(pad "127" smd rect
			(at 0 112.199928 270)
			(size 1.8034 0.508)
			(layers "B.Cu" "B.Mask" "B.Paste")
			(net "GND")
		)
		(pad "128" smd rect
			(at 0 113.050066 270)
			(size 1.8034 0.508)
			(layers "B.Cu" "B.Mask" "B.Paste")
			(net "M_B_DQ<60>")
		)
		(pad "129" smd rect
			(at 0 113.89995 270)
			(size 1.8034 0.508)
			(layers "B.Cu" "B.Mask" "B.Paste")
			(net "GND")
		)
		(pad "130" smd rect
			(at 0 114.750088 270)
			(size 1.8034 0.508)
			(layers "B.Cu" "B.Mask" "B.Paste")
			(net "M_B_DQ<56>")
		)
		(pad "131" smd rect
			(at 0 115.599972 270)
			(size 1.8034 0.508)
			(layers "B.Cu" "B.Mask" "B.Paste")
			(net "GND")
		)
		(pad "132" smd rect
			(at 0 116.45011 270)
			(size 1.8034 0.508)
			(layers "B.Cu" "B.Mask" "B.Paste")
			(net "M_B_DQS_DP<16>")
		)
		(pad "133" smd rect
			(at 0 117.299994 270)
			(size 1.8034 0.508)
			(layers "B.Cu" "B.Mask" "B.Paste")
			(net "M_B_DQS_DN<16>")
		)
		(pad "134" smd rect
			(at 0 118.149878 270)
			(size 1.8034 0.508)
			(layers "B.Cu" "B.Mask" "B.Paste")
			(net "GND")
		)
		(pad "135" smd rect
			(at 0 119.000016 270)
			(size 1.8034 0.508)
			(layers "B.Cu" "B.Mask" "B.Paste")
			(net "M_B_DQ<62>")
		)
		(pad "136" smd rect
			(at 0 119.8499 270)
			(size 1.8034 0.508)
			(layers "B.Cu" "B.Mask" "B.Paste")
			(net "GND")
		)
		(pad "137" smd rect
			(at 0 120.700038 270)
			(size 1.8034 0.508)
			(layers "B.Cu" "B.Mask" "B.Paste")
			(net "M_B_DQ<58>")
		)
		(pad "138" smd rect
			(at 0 121.549922 270)
			(size 1.8034 0.508)
			(layers "B.Cu" "B.Mask" "B.Paste")
			(net "GND")
		)
		(pad "139" smd rect
			(at 0 122.40006 270)
			(size 1.8034 0.508)
			(layers "B.Cu" "B.Mask" "B.Paste")
			(net "PVPP_ABC")
		)
		(pad "140" smd rect
			(at 0 123.249944 270)
			(size 1.8034 0.508)
			(layers "B.Cu" "B.Mask" "B.Paste")
			(net "PVPP_ABC")
		)
		(pad "141" smd rect
			(at 0 124.100082 270)
			(size 1.8034 0.508)
			(layers "B.Cu" "B.Mask" "B.Paste")
			(net "SMB_DDR_ABC_VPP_SCL")
		)
		(pad "142" smd rect
			(at 0 124.949966 270)
			(size 1.8034 0.508)
			(layers "B.Cu" "B.Mask" "B.Paste")
			(net "PVPP_ABC")
		)
		(pad "143" smd rect
			(at 0 125.800104 270)
			(size 1.8034 0.508)
			(layers "B.Cu" "B.Mask" "B.Paste")
			(net "PVPP_ABC")
		)
		(pad "144" smd rect
			(at 0 126.649988 270)
			(size 1.8034 0.508)
			(layers "B.Cu" "B.Mask" "B.Paste")
			(net "TP_CH_B_DIMM_B1_RFU_2")
		)
		(pad "145" smd rect
			(at -4.59994 0 270)
			(size 1.8034 0.508)
			(layers "B.Cu" "B.Mask" "B.Paste")
			(net "P12V_NVDIMM_ABC")
		)
		(pad "146" smd rect
			(at -4.59994 0.849884 270)
			(size 1.8034 0.508)
			(layers "B.Cu" "B.Mask" "B.Paste")
			(net "M_B_VREF")
		)
		(pad "147" smd rect
			(at -4.59994 1.700022 270)
			(size 1.8034 0.508)
			(layers "B.Cu" "B.Mask" "B.Paste")
			(net "GND")
		)
		(pad "148" smd rect
			(at -4.59994 2.549906 270)
			(size 1.8034 0.508)
			(layers "B.Cu" "B.Mask" "B.Paste")
			(net "M_B_DQ<5>")
		)
		(pad "149" smd rect
			(at -4.59994 3.400044 270)
			(size 1.8034 0.508)
			(layers "B.Cu" "B.Mask" "B.Paste")
			(net "GND")
		)
		(pad "150" smd rect
			(at -4.59994 4.249928 270)
			(size 1.8034 0.508)
			(layers "B.Cu" "B.Mask" "B.Paste")
			(net "M_B_DQ<1>")
		)
		(pad "151" smd rect
			(at -4.59994 5.100066 270)
			(size 1.8034 0.508)
			(layers "B.Cu" "B.Mask" "B.Paste")
			(net "GND")
		)
		(pad "152" smd rect
			(at -4.59994 5.94995 270)
			(size 1.8034 0.508)
			(layers "B.Cu" "B.Mask" "B.Paste")
			(net "M_B_DQS_DN<0>")
		)
		(pad "153" smd rect
			(at -4.59994 6.800088 270)
			(size 1.8034 0.508)
			(layers "B.Cu" "B.Mask" "B.Paste")
			(net "M_B_DQS_DP<0>")
		)
		(pad "154" smd rect
			(at -4.59994 7.649972 270)
			(size 1.8034 0.508)
			(layers "B.Cu" "B.Mask" "B.Paste")
			(net "GND")
		)
		(pad "155" smd rect
			(at -4.59994 8.50011 270)
			(size 1.8034 0.508)
			(layers "B.Cu" "B.Mask" "B.Paste")
			(net "M_B_DQ<7>")
		)
		(pad "156" smd rect
			(at -4.59994 9.349994 270)
			(size 1.8034 0.508)
			(layers "B.Cu" "B.Mask" "B.Paste")
			(net "GND")
		)
		(pad "157" smd rect
			(at -4.59994 10.199878 270)
			(size 1.8034 0.508)
			(layers "B.Cu" "B.Mask" "B.Paste")
			(net "M_B_DQ<3>")
		)
		(pad "158" smd rect
			(at -4.59994 11.050016 270)
			(size 1.8034 0.508)
			(layers "B.Cu" "B.Mask" "B.Paste")
			(net "GND")
		)
		(pad "159" smd rect
			(at -4.59994 11.8999 270)
			(size 1.8034 0.508)
			(layers "B.Cu" "B.Mask" "B.Paste")
			(net "M_B_DQ<13>")
		)
		(pad "160" smd rect
			(at -4.59994 12.750038 270)
			(size 1.8034 0.508)
			(layers "B.Cu" "B.Mask" "B.Paste")
			(net "GND")
		)
		(pad "161" smd rect
			(at -4.59994 13.599922 270)
			(size 1.8034 0.508)
			(layers "B.Cu" "B.Mask" "B.Paste")
			(net "M_B_DQ<9>")
		)
		(pad "162" smd rect
			(at -4.59994 14.45006 270)
			(size 1.8034 0.508)
			(layers "B.Cu" "B.Mask" "B.Paste")
			(net "GND")
		)
		(pad "163" smd rect
			(at -4.59994 15.299944 270)
			(size 1.8034 0.508)
			(layers "B.Cu" "B.Mask" "B.Paste")
			(net "M_B_DQS_DN<1>")
		)
		(pad "164" smd rect
			(at -4.59994 16.150082 270)
			(size 1.8034 0.508)
			(layers "B.Cu" "B.Mask" "B.Paste")
			(net "M_B_DQS_DP<1>")
		)
		(pad "165" smd rect
			(at -4.59994 16.999966 270)
			(size 1.8034 0.508)
			(layers "B.Cu" "B.Mask" "B.Paste")
			(net "GND")
		)
		(pad "166" smd rect
			(at -4.59994 17.850104 270)
			(size 1.8034 0.508)
			(layers "B.Cu" "B.Mask" "B.Paste")
			(net "M_B_DQ<15>")
		)
		(pad "167" smd rect
			(at -4.59994 18.699988 270)
			(size 1.8034 0.508)
			(layers "B.Cu" "B.Mask" "B.Paste")
			(net "GND")
		)
		(pad "168" smd rect
			(at -4.59994 19.550126 270)
			(size 1.8034 0.508)
			(layers "B.Cu" "B.Mask" "B.Paste")
			(net "M_B_DQ<11>")
		)
		(pad "169" smd rect
			(at -4.59994 20.40001 270)
			(size 1.8034 0.508)
			(layers "B.Cu" "B.Mask" "B.Paste")
			(net "GND")
		)
		(pad "170" smd rect
			(at -4.59994 21.249894 270)
			(size 1.8034 0.508)
			(layers "B.Cu" "B.Mask" "B.Paste")
			(net "M_B_DQ<21>")
		)
		(pad "171" smd rect
			(at -4.59994 22.100032 270)
			(size 1.8034 0.508)
			(layers "B.Cu" "B.Mask" "B.Paste")
			(net "GND")
		)
		(pad "172" smd rect
			(at -4.59994 22.949916 270)
			(size 1.8034 0.508)
			(layers "B.Cu" "B.Mask" "B.Paste")
			(net "M_B_DQ<17>")
		)
		(pad "173" smd rect
			(at -4.59994 23.800054 270)
			(size 1.8034 0.508)
			(layers "B.Cu" "B.Mask" "B.Paste")
			(net "GND")
		)
		(pad "174" smd rect
			(at -4.59994 24.649938 270)
			(size 1.8034 0.508)
			(layers "B.Cu" "B.Mask" "B.Paste")
			(net "M_B_DQS_DN<2>")
		)
		(pad "175" smd rect
			(at -4.59994 25.500076 270)
			(size 1.8034 0.508)
			(layers "B.Cu" "B.Mask" "B.Paste")
			(net "M_B_DQS_DP<2>")
		)
		(pad "176" smd rect
			(at -4.59994 26.34996 270)
			(size 1.8034 0.508)
			(layers "B.Cu" "B.Mask" "B.Paste")
			(net "GND")
		)
		(pad "177" smd rect
			(at -4.59994 27.200098 270)
			(size 1.8034 0.508)
			(layers "B.Cu" "B.Mask" "B.Paste")
			(net "M_B_DQ<23>")
		)
		(pad "178" smd rect
			(at -4.59994 28.049982 270)
			(size 1.8034 0.508)
			(layers "B.Cu" "B.Mask" "B.Paste")
			(net "GND")
		)
		(pad "179" smd rect
			(at -4.59994 28.90012 270)
			(size 1.8034 0.508)
			(layers "B.Cu" "B.Mask" "B.Paste")
			(net "M_B_DQ<19>")
		)
		(pad "180" smd rect
			(at -4.59994 29.750004 270)
			(size 1.8034 0.508)
			(layers "B.Cu" "B.Mask" "B.Paste")
			(net "GND")
		)
		(pad "181" smd rect
			(at -4.59994 30.599888 270)
			(size 1.8034 0.508)
			(layers "B.Cu" "B.Mask" "B.Paste")
			(net "M_B_DQ<29>")
		)
		(pad "182" smd rect
			(at -4.59994 31.450026 270)
			(size 1.8034 0.508)
			(layers "B.Cu" "B.Mask" "B.Paste")
			(net "GND")
		)
		(pad "183" smd rect
			(at -4.59994 32.29991 270)
			(size 1.8034 0.508)
			(layers "B.Cu" "B.Mask" "B.Paste")
			(net "M_B_DQ<25>")
		)
		(pad "184" smd rect
			(at -4.59994 33.150048 270)
			(size 1.8034 0.508)
			(layers "B.Cu" "B.Mask" "B.Paste")
			(net "GND")
		)
		(pad "185" smd rect
			(at -4.59994 33.999932 270)
			(size 1.8034 0.508)
			(layers "B.Cu" "B.Mask" "B.Paste")
			(net "M_B_DQS_DN<3>")
		)
		(pad "186" smd rect
			(at -4.59994 34.85007 270)
			(size 1.8034 0.508)
			(layers "B.Cu" "B.Mask" "B.Paste")
			(net "M_B_DQS_DP<3>")
		)
		(pad "187" smd rect
			(at -4.59994 35.699954 270)
			(size 1.8034 0.508)
			(layers "B.Cu" "B.Mask" "B.Paste")
			(net "GND")
		)
		(pad "188" smd rect
			(at -4.59994 36.550092 270)
			(size 1.8034 0.508)
			(layers "B.Cu" "B.Mask" "B.Paste")
			(net "M_B_DQ<31>")
		)
		(pad "189" smd rect
			(at -4.59994 37.399976 270)
			(size 1.8034 0.508)
			(layers "B.Cu" "B.Mask" "B.Paste")
			(net "GND")
		)
		(pad "190" smd rect
			(at -4.59994 38.250114 270)
			(size 1.8034 0.508)
			(layers "B.Cu" "B.Mask" "B.Paste")
			(net "M_B_DQ<27>")
		)
		(pad "191" smd rect
			(at -4.59994 39.099998 270)
			(size 1.8034 0.508)
			(layers "B.Cu" "B.Mask" "B.Paste")
			(net "GND")
		)
		(pad "192" smd rect
			(at -4.59994 39.949882 270)
			(size 1.8034 0.508)
			(layers "B.Cu" "B.Mask" "B.Paste")
			(net "M_B_ECC<5>")
		)
		(pad "193" smd rect
			(at -4.59994 40.80002 270)
			(size 1.8034 0.508)
			(layers "B.Cu" "B.Mask" "B.Paste")
			(net "GND")
		)
		(pad "194" smd rect
			(at -4.59994 41.649904 270)
			(size 1.8034 0.508)
			(layers "B.Cu" "B.Mask" "B.Paste")
			(net "M_B_ECC<1>")
		)
		(pad "195" smd rect
			(at -4.59994 42.500042 270)
			(size 1.8034 0.508)
			(layers "B.Cu" "B.Mask" "B.Paste")
			(net "GND")
		)
		(pad "196" smd rect
			(at -4.59994 43.349926 270)
			(size 1.8034 0.508)
			(layers "B.Cu" "B.Mask" "B.Paste")
			(net "M_B_DQS_DN<8>")
		)
		(pad "197" smd rect
			(at -4.59994 44.200064 270)
			(size 1.8034 0.508)
			(layers "B.Cu" "B.Mask" "B.Paste")
			(net "M_B_DQS_DP<8>")
		)
		(pad "198" smd rect
			(at -4.59994 45.049948 270)
			(size 1.8034 0.508)
			(layers "B.Cu" "B.Mask" "B.Paste")
			(net "GND")
		)
		(pad "199" smd rect
			(at -4.59994 45.900086 270)
			(size 1.8034 0.508)
			(layers "B.Cu" "B.Mask" "B.Paste")
			(net "M_B_ECC<7>")
		)
		(pad "200" smd rect
			(at -4.59994 46.74997 270)
			(size 1.8034 0.508)
			(layers "B.Cu" "B.Mask" "B.Paste")
			(net "GND")
		)
		(pad "201" smd rect
			(at -4.59994 47.600108 270)
			(size 1.8034 0.508)
			(layers "B.Cu" "B.Mask" "B.Paste")
			(net "M_B_ECC<3>")
		)
		(pad "202" smd rect
			(at -4.59994 48.449992 270)
			(size 1.8034 0.508)
			(layers "B.Cu" "B.Mask" "B.Paste")
			(net "GND")
		)
		(pad "203" smd rect
			(at -4.59994 49.299876 270)
			(size 1.8034 0.508)
			(layers "B.Cu" "B.Mask" "B.Paste")
			(net "M_B_CKE<3>")
		)
		(pad "204" smd rect
			(at -4.59994 50.150014 270)
			(size 1.8034 0.508)
			(layers "B.Cu" "B.Mask" "B.Paste")
			(net "PVDDQ_ABC")
		)
		(pad "205" smd rect
			(at -4.59994 50.999898 270)
			(size 1.8034 0.508)
			(layers "B.Cu" "B.Mask" "B.Paste")
			(net "TP_CH_B_DIMM_B1_RFU_0")
		)
		(pad "206" smd rect
			(at -4.59994 51.850036 270)
			(size 1.8034 0.508)
			(layers "B.Cu" "B.Mask" "B.Paste")
			(net "PVDDQ_ABC")
		)
		(pad "207" smd rect
			(at -4.59994 52.69992 270)
			(size 1.8034 0.508)
			(layers "B.Cu" "B.Mask" "B.Paste")
			(net "M_B_BG<1>")
		)
		(pad "208" smd rect
			(at -4.59994 53.550058 270)
			(size 1.8034 0.508)
			(layers "B.Cu" "B.Mask" "B.Paste")
			(net "M_B_ALERT_N")
		)
		(pad "209" smd rect
			(at -4.59994 54.399942 270)
			(size 1.8034 0.508)
			(layers "B.Cu" "B.Mask" "B.Paste")
			(net "PVDDQ_ABC")
		)
		(pad "210" smd rect
			(at -4.59994 55.25008 270)
			(size 1.8034 0.508)
			(layers "B.Cu" "B.Mask" "B.Paste")
			(net "M_B_MA<11>")
		)
		(pad "211" smd rect
			(at -4.59994 56.099964 270)
			(size 1.8034 0.508)
			(layers "B.Cu" "B.Mask" "B.Paste")
			(net "M_B_MA<7>")
		)
		(pad "212" smd rect
			(at -4.59994 56.950102 270)
			(size 1.8034 0.508)
			(layers "B.Cu" "B.Mask" "B.Paste")
			(net "PVDDQ_ABC")
		)
		(pad "213" smd rect
			(at -4.59994 57.799986 270)
			(size 1.8034 0.508)
			(layers "B.Cu" "B.Mask" "B.Paste")
			(net "M_B_MA<5>")
		)
		(pad "214" smd rect
			(at -4.59994 58.650124 270)
			(size 1.8034 0.508)
			(layers "B.Cu" "B.Mask" "B.Paste")
			(net "M_B_MA<4>")
		)
		(pad "215" smd rect
			(at -4.59994 59.500008 270)
			(size 1.8034 0.508)
			(layers "B.Cu" "B.Mask" "B.Paste")
			(net "PVDDQ_ABC")
		)
		(pad "216" smd rect
			(at -4.59994 60.349892 270)
			(size 1.8034 0.508)
			(layers "B.Cu" "B.Mask" "B.Paste")
			(net "M_B_MA<2>")
		)
		(pad "217" smd rect
			(at -4.59994 61.20003 270)
			(size 1.8034 0.508)
			(layers "B.Cu" "B.Mask" "B.Paste")
			(net "PVDDQ_ABC")
		)
		(pad "218" smd rect
			(at -4.59994 62.049914 270)
			(size 1.8034 0.508)
			(layers "B.Cu" "B.Mask" "B.Paste")
			(net "M_B_CLK_DP<3>")
		)
		(pad "219" smd rect
			(at -4.59994 62.900052 270)
			(size 1.8034 0.508)
			(layers "B.Cu" "B.Mask" "B.Paste")
			(net "M_B_CLK_DN<3>")
		)
		(pad "220" smd rect
			(at -4.59994 63.749936 270)
			(size 1.8034 0.508)
			(layers "B.Cu" "B.Mask" "B.Paste")
			(net "PVDDQ_ABC")
		)
		(pad "221" smd rect
			(at -4.59994 64.600074 270)
			(size 1.8034 0.508)
			(layers "B.Cu" "B.Mask" "B.Paste")
			(net "PVTT_ABC")
		)
		(pad "222" smd rect
			(at -4.59994 70.550024 270)
			(size 1.8034 0.508)
			(layers "B.Cu" "B.Mask" "B.Paste")
			(net "M_B_PAR")
		)
		(pad "223" smd rect
			(at -4.59994 71.399908 270)
			(size 1.8034 0.508)
			(layers "B.Cu" "B.Mask" "B.Paste")
			(net "PVDDQ_ABC")
		)
		(pad "224" smd rect
			(at -4.59994 72.250046 270)
			(size 1.8034 0.508)
			(layers "B.Cu" "B.Mask" "B.Paste")
			(net "M_B_BA<1>")
		)
		(pad "225" smd rect
			(at -4.59994 73.09993 270)
			(size 1.8034 0.508)
			(layers "B.Cu" "B.Mask" "B.Paste")
			(net "M_B_MA<10>")
		)
		(pad "226" smd rect
			(at -4.59994 73.950068 270)
			(size 1.8034 0.508)
			(layers "B.Cu" "B.Mask" "B.Paste")
			(net "PVDDQ_ABC")
		)
		(pad "227" smd rect
			(at -4.59994 74.799952 270)
			(size 1.8034 0.508)
			(layers "B.Cu" "B.Mask" "B.Paste")
			(net "TP_CH_B_DIMM_B1_RFU_1")
		)
		(pad "228" smd rect
			(at -4.59994 75.65009 270)
			(size 1.8034 0.508)
			(layers "B.Cu" "B.Mask" "B.Paste")
			(net "M_B_MA<14>")
		)
		(pad "229" smd rect
			(at -4.59994 76.499974 270)
			(size 1.8034 0.508)
			(layers "B.Cu" "B.Mask" "B.Paste")
			(net "PVDDQ_ABC")
		)
		(pad "230" smd rect
			(at -4.59994 77.350112 270)
			(size 1.8034 0.508)
			(layers "B.Cu" "B.Mask" "B.Paste")
			(net "FM_ADR_COMPLETE_ABC_N")
		)
		(pad "231" smd rect
			(at -4.59994 78.199996 270)
			(size 1.8034 0.508)
			(layers "B.Cu" "B.Mask" "B.Paste")
			(net "PVDDQ_ABC")
		)
		(pad "232" smd rect
			(at -4.59994 79.04988 270)
			(size 1.8034 0.508)
			(layers "B.Cu" "B.Mask" "B.Paste")
			(net "M_B_MA<13>")
		)
		(pad "233" smd rect
			(at -4.59994 79.900018 270)
			(size 1.8034 0.508)
			(layers "B.Cu" "B.Mask" "B.Paste")
			(net "PVDDQ_ABC")
		)
		(pad "234" smd rect
			(at -4.59994 80.749902 270)
			(size 1.8034 0.508)
			(layers "B.Cu" "B.Mask" "B.Paste")
			(net "M_B_MA<17>")
		)
		(pad "235" smd rect
			(at -4.59994 81.60004 270)
			(size 1.8034 0.508)
			(layers "B.Cu" "B.Mask" "B.Paste")
			(net "M_B_C<2>")
		)
		(pad "236" smd rect
			(at -4.59994 82.449924 270)
			(size 1.8034 0.508)
			(layers "B.Cu" "B.Mask" "B.Paste")
			(net "PVDDQ_ABC")
		)
		(pad "237" smd rect
			(at -4.59994 83.300062 270)
			(size 1.8034 0.508)
			(layers "B.Cu" "B.Mask" "B.Paste")
			(net "M_B_CS_N<7>")
		)
		(pad "238" smd rect
			(at -4.59994 84.149946 270)
			(size 1.8034 0.508)
			(layers "B.Cu" "B.Mask" "B.Paste")
			(net "GND")
		)
		(pad "239" smd rect
			(at -4.59994 85.000084 270)
			(size 1.8034 0.508)
			(layers "B.Cu" "B.Mask" "B.Paste")
			(net "GND")
		)
		(pad "240" smd rect
			(at -4.59994 85.849968 270)
			(size 1.8034 0.508)
			(layers "B.Cu" "B.Mask" "B.Paste")
			(net "M_B_DQ<37>")
		)
	)
)
